FILE_TYPE = MULTI_PHYS_TABLE;

PART 'CONN_64P_GF'
CLASS = IO 

{========================================================================================}
: CLS_PN              =  JEDEC_TYPE        | ALT_SYMBOLS         | DESCRIPTION                                  ;
{========================================================================================}
 'S_M_EF64_PCIE_P0394_V1'      = 'S_M_EF64_PCIE_P0394_V1'  |'(S_M_EF64_PCIE_P0394_V1)'  |'GOLDEN FINGER FOR MPN 10061913-101TLF,64PIN'    
 
END_PART

END.

